(kicad_pcb
	(version 20260206)
	(generator "pcbnew")
	(generator_version "10.0")
	(general
		(thickness 1.6)
		(legacy_teardrops no)
	)
	(paper "A4")
	(title_block
		(title "Wiwynn_Tioga_Pass_MB.brd")
		(comment 1 "Tioga Pass / footprints 796-802 of 4770")
	)
	(layers
		(0 "F.Cu" signal "TOP")
		(4 "In1.Cu" signal "L2GND")
		(6 "In2.Cu" signal "L3")
		(8 "In3.Cu" signal "L4GND")
		(10 "In4.Cu" signal "L5")
		(12 "In5.Cu" signal "L6GND")
		(14 "In6.Cu" signal "L7VCC")
		(16 "In7.Cu" signal "L8VCC")
		(18 "In8.Cu" signal "L9GND")
		(20 "In9.Cu" signal "L10")
		(22 "In10.Cu" signal "L11GND")
		(24 "In11.Cu" signal "L12")
		(26 "In12.Cu" signal "L13GND")
		(2 "B.Cu" signal "BOTTOM")
		(9 "F.Adhes" user "F.Adhesive")
		(11 "B.Adhes" user "B.Adhesive")
		(13 "F.Paste" user "Package Geometry/Pastemask Top")
		(15 "B.Paste" user "Package Geometry/Pastemask Bottom")
		(5 "F.SilkS" user "Ref Des/Silkscreen Top")
		(7 "B.SilkS" user "Ref Des/Silkscreen Bottom")
		(1 "F.Mask" user "Board Geometry/Soldermask Top")
		(3 "B.Mask" user "Board Geometry/Soldermask Bottom")
		(17 "Dwgs.User" user "User.Drawings")
		(19 "Cmts.User" user "User.Comments")
		(21 "Eco1.User" user "User.Eco1")
		(23 "Eco2.User" user "User.Eco2")
		(25 "Edge.Cuts" user "Board Geometry/Outline")
		(27 "Margin" user)
		(31 "F.CrtYd" user "Package Geometry/Place Bound Top")
		(29 "B.CrtYd" user "Package Geometry/Place Bound Bottom")
		(35 "F.Fab" user "Ref Des/Assembly Top")
		(33 "B.Fab" user "Ref Des/Assembly Bottom")
	)
	(footprint ""
		(layer "F.Cu")
		(at 17.0434 -41.5036 -90)
		(property "Reference" "C1E22"
			(at 0 0 270)
			(layer "F.SilkS")
			(hide yes)
			(effects
				(font
					(size 1.27 1.27)
				)
			)
		)
		(property "Value" ""
			(at 0 0 270)
			(layer "F.Fab")
			(effects
				(font
					(size 1.27 1.27)
				)
			)
		)
		(duplicate_pad_numbers_are_jumpers no)
		(fp_poly
			(pts
				(xy 0.3048 -0.1016) (xy 0.3048 0.9906) (xy -0.3048 0.9906) (xy -0.3048 -0.1016)
			)
			(stroke
				(width 0)
				(type default)
			)
			(fill no)
			(layer "F.CrtYd")
		)
		(fp_line
			(start -0.3048 0.9906)
			(end 0.3048 0.9906)
			(stroke
				(width 0.1)
				(type default)
			)
			(layer "F.Fab")
		)
		(fp_line
			(start 0.3048 0.9906)
			(end 0.3048 -0.1016)
			(stroke
				(width 0.1)
				(type default)
			)
			(layer "F.Fab")
		)
		(fp_line
			(start -0.3048 -0.1016)
			(end -0.3048 0.9906)
			(stroke
				(width 0.1)
				(type default)
			)
			(layer "F.Fab")
		)
		(fp_line
			(start 0.3048 -0.1016)
			(end -0.3048 -0.1016)
			(stroke
				(width 0.1)
				(type default)
			)
			(layer "F.Fab")
		)
		(pad "1" smd rect
			(at 0 0 270)
			(size 0.508 0.508)
			(layers "F.Cu" "F.Mask" "F.Paste")
			(net "P3V3_STBY")
		)
		(pad "2" smd rect
			(at 0 0.889 270)
			(size 0.508 0.508)
			(layers "F.Cu" "F.Mask" "F.Paste")
			(net "GND")
		)
		(zone
			(layer "F.Cu")
			(hatch none 0.5)
			(connect_pads
				(clearance 0)
			)
			(min_thickness 0.25)
			(keepout
				(tracks not_allowed)
				(vias allowed)
				(pads allowed)
				(copperpour not_allowed)
				(footprints allowed)
			)
			(placement
				(enabled no)
				(sheetname "")
			)
			(fill
				(thermal_gap 0.5)
				(thermal_bridge_width 0.5)
				(island_removal_mode 0)
			)
			(polygon
				(pts
					(xy 16.4084 -41.7576) (xy 16.4084 -41.2496) (xy 16.7894 -41.2496) (xy 16.7894 -41.7576)
				)
			)
		)
		(zone
			(layer "F.Cu")
			(hatch none 0.5)
			(connect_pads
				(clearance 0)
			)
			(min_thickness 0.25)
			(keepout
				(tracks allowed)
				(vias not_allowed)
				(pads allowed)
				(copperpour not_allowed)
				(footprints allowed)
			)
			(placement
				(enabled no)
				(sheetname "")
			)
			(fill
				(thermal_gap 0.5)
				(thermal_bridge_width 0.5)
				(island_removal_mode 0)
			)
			(polygon
				(pts
					(xy 16.7894 -41.7576) (xy 16.7894 -41.2496) (xy 16.4084 -41.2496) (xy 16.4084 -41.7576)
				)
			)
		)
	)
	(footprint ""
		(layer "F.Cu")
		(at 406.9461 -62.611 90)
		(property "Reference" "R8E13"
			(at 0 0 90)
			(layer "F.SilkS")
			(hide yes)
			(effects
				(font
					(size 1.27 1.27)
				)
			)
		)
		(property "Value" ""
			(at 0 0 90)
			(layer "F.Fab")
			(effects
				(font
					(size 1.27 1.27)
				)
			)
		)
		(duplicate_pad_numbers_are_jumpers no)
		(fp_poly
			(pts
				(xy -0.2794 -0.1016) (xy 0.2794 -0.1016) (xy 0.2794 0.9906) (xy -0.2794 0.9906)
			)
			(stroke
				(width 0)
				(type default)
			)
			(fill no)
			(layer "F.CrtYd")
		)
		(pad "1" smd rect
			(at 0 0 90)
			(size 0.508 0.508)
			(layers "F.Cu" "F.Mask" "F.Paste")
			(net "SPI_PCH_MISO")
		)
		(pad "2" smd rect
			(at 0 0.889 90)
			(size 0.508 0.508)
			(layers "F.Cu" "F.Mask" "F.Paste")
			(net "SPI_PCH_TPM_MISO_R")
		)
		(zone
			(layer "F.Cu")
			(hatch none 0.5)
			(connect_pads
				(clearance 0)
			)
			(min_thickness 0.25)
			(keepout
				(tracks allowed)
				(vias not_allowed)
				(pads allowed)
				(copperpour not_allowed)
				(footprints allowed)
			)
			(placement
				(enabled no)
				(sheetname "")
			)
			(fill
				(thermal_gap 0.5)
				(thermal_bridge_width 0.5)
				(island_removal_mode 0)
			)
			(polygon
				(pts
					(xy 407.2001 -62.357) (xy 407.2001 -62.865) (xy 407.5811 -62.865) (xy 407.5811 -62.357)
				)
			)
		)
		(zone
			(layer "F.Cu")
			(hatch none 0.5)
			(connect_pads
				(clearance 0)
			)
			(min_thickness 0.25)
			(keepout
				(tracks not_allowed)
				(vias allowed)
				(pads allowed)
				(copperpour not_allowed)
				(footprints allowed)
			)
			(placement
				(enabled no)
				(sheetname "")
			)
			(fill
				(thermal_gap 0.5)
				(thermal_bridge_width 0.5)
				(island_removal_mode 0)
			)
			(polygon
				(pts
					(xy 407.5811 -62.357) (xy 407.5811 -62.865) (xy 407.2001 -62.865) (xy 407.2001 -62.357)
				)
			)
		)
	)
	(footprint ""
		(layer "F.Cu")
		(at 389.0645 -80.6196 -90)
		(property "Reference" "C7D5"
			(at 0 0 270)
			(layer "F.SilkS")
			(hide yes)
			(effects
				(font
					(size 1.27 1.27)
				)
			)
		)
		(property "Value" ""
			(at 0 0 270)
			(layer "F.Fab")
			(effects
				(font
					(size 1.27 1.27)
				)
			)
		)
		(duplicate_pad_numbers_are_jumpers no)
		(fp_poly
			(pts
				(xy 0.3048 -0.1016) (xy 0.3048 0.9906) (xy -0.3048 0.9906) (xy -0.3048 -0.1016)
			)
			(stroke
				(width 0)
				(type default)
			)
			(fill no)
			(layer "F.CrtYd")
		)
		(fp_line
			(start -0.3048 0.9906)
			(end 0.3048 0.9906)
			(stroke
				(width 0.1)
				(type default)
			)
			(layer "F.Fab")
		)
		(fp_line
			(start 0.3048 0.9906)
			(end 0.3048 -0.1016)
			(stroke
				(width 0.1)
				(type default)
			)
			(layer "F.Fab")
		)
		(fp_line
			(start -0.3048 -0.1016)
			(end -0.3048 0.9906)
			(stroke
				(width 0.1)
				(type default)
			)
			(layer "F.Fab")
		)
		(fp_line
			(start 0.3048 -0.1016)
			(end -0.3048 -0.1016)
			(stroke
				(width 0.1)
				(type default)
			)
			(layer "F.Fab")
		)
		(pad "1" smd rect
			(at 0 0 270)
			(size 0.508 0.508)
			(layers "F.Cu" "F.Mask" "F.Paste")
			(net "P0V7_GTL2104_VREF_0")
		)
		(pad "2" smd rect
			(at 0 0.889 270)
			(size 0.508 0.508)
			(layers "F.Cu" "F.Mask" "F.Paste")
			(net "GND")
		)
		(zone
			(layer "F.Cu")
			(hatch none 0.5)
			(connect_pads
				(clearance 0)
			)
			(min_thickness 0.25)
			(keepout
				(tracks not_allowed)
				(vias allowed)
				(pads allowed)
				(copperpour not_allowed)
				(footprints allowed)
			)
			(placement
				(enabled no)
				(sheetname "")
			)
			(fill
				(thermal_gap 0.5)
				(thermal_bridge_width 0.5)
				(island_removal_mode 0)
			)
			(polygon
				(pts
					(xy 388.4295 -80.8736) (xy 388.4295 -80.3656) (xy 388.8105 -80.3656) (xy 388.8105 -80.8736)
				)
			)
		)
		(zone
			(layer "F.Cu")
			(hatch none 0.5)
			(connect_pads
				(clearance 0)
			)
			(min_thickness 0.25)
			(keepout
				(tracks allowed)
				(vias not_allowed)
				(pads allowed)
				(copperpour not_allowed)
				(footprints allowed)
			)
			(placement
				(enabled no)
				(sheetname "")
			)
			(fill
				(thermal_gap 0.5)
				(thermal_bridge_width 0.5)
				(island_removal_mode 0)
			)
			(polygon
				(pts
					(xy 388.8105 -80.8736) (xy 388.8105 -80.3656) (xy 388.4295 -80.3656) (xy 388.4295 -80.8736)
				)
			)
		)
	)
	(footprint ""
		(layer "F.Cu")
		(at 205.0288 -49.6824 90)
		(property "Reference" "R4E17"
			(at 0 0 90)
			(layer "F.SilkS")
			(hide yes)
			(effects
				(font
					(size 1.27 1.27)
				)
			)
		)
		(property "Value" ""
			(at 0 0 90)
			(layer "F.Fab")
			(effects
				(font
					(size 1.27 1.27)
				)
			)
		)
		(duplicate_pad_numbers_are_jumpers no)
		(fp_poly
			(pts
				(xy -0.2794 -0.1016) (xy 0.2794 -0.1016) (xy 0.2794 0.9906) (xy -0.2794 0.9906)
			)
			(stroke
				(width 0)
				(type default)
			)
			(fill no)
			(layer "F.CrtYd")
		)
		(fp_line
			(start 0.2794 -0.1016)
			(end -0.2794 -0.1016)
			(stroke
				(width 0.1)
				(type default)
			)
			(layer "F.Fab")
		)
		(fp_line
			(start -0.2794 -0.1016)
			(end -0.2794 0.9906)
			(stroke
				(width 0.1)
				(type default)
			)
			(layer "F.Fab")
		)
		(fp_line
			(start 0.2794 0.9906)
			(end 0.2794 -0.1016)
			(stroke
				(width 0.1)
				(type default)
			)
			(layer "F.Fab")
		)
		(fp_line
			(start -0.2794 0.9906)
			(end 0.2794 0.9906)
			(stroke
				(width 0.1)
				(type default)
			)
			(layer "F.Fab")
		)
		(pad "1" smd rect
			(at 0 0 90)
			(size 0.508 0.508)
			(layers "F.Cu" "F.Mask" "F.Paste")
			(net "VSENSE_PVCCIN_CPU0_N")
		)
		(pad "2" smd rect
			(at 0 0.889 90)
			(size 0.508 0.508)
			(layers "F.Cu" "F.Mask" "F.Paste")
			(net "VSENSE_PVCCIN_CPU0_SKT_VRTN")
		)
		(zone
			(layer "F.Cu")
			(hatch none 0.5)
			(connect_pads
				(clearance 0)
			)
			(min_thickness 0.25)
			(keepout
				(tracks allowed)
				(vias not_allowed)
				(pads allowed)
				(copperpour not_allowed)
				(footprints allowed)
			)
			(placement
				(enabled no)
				(sheetname "")
			)
			(fill
				(thermal_gap 0.5)
				(thermal_bridge_width 0.5)
				(island_removal_mode 0)
			)
			(polygon
				(pts
					(xy 205.2828 -49.4284) (xy 205.2828 -49.9364) (xy 205.6638 -49.9364) (xy 205.6638 -49.4284)
				)
			)
		)
		(zone
			(layer "F.Cu")
			(hatch none 0.5)
			(connect_pads
				(clearance 0)
			)
			(min_thickness 0.25)
			(keepout
				(tracks not_allowed)
				(vias allowed)
				(pads allowed)
				(copperpour not_allowed)
				(footprints allowed)
			)
			(placement
				(enabled no)
				(sheetname "")
			)
			(fill
				(thermal_gap 0.5)
				(thermal_bridge_width 0.5)
				(island_removal_mode 0)
			)
			(polygon
				(pts
					(xy 205.6638 -49.4284) (xy 205.6638 -49.9364) (xy 205.2828 -49.9364) (xy 205.2828 -49.4284)
				)
			)
		)
	)
	(footprint ""
		(layer "F.Cu")
		(at 339.6742 -105.029 90)
		(property "Reference" "R7C3"
			(at 0 0 90)
			(layer "F.SilkS")
			(hide yes)
			(effects
				(font
					(size 1.27 1.27)
				)
			)
		)
		(property "Value" ""
			(at 0 0 90)
			(layer "F.Fab")
			(effects
				(font
					(size 1.27 1.27)
				)
			)
		)
		(duplicate_pad_numbers_are_jumpers no)
		(fp_poly
			(pts
				(xy -0.2794 -0.1016) (xy 0.2794 -0.1016) (xy 0.2794 0.9906) (xy -0.2794 0.9906)
			)
			(stroke
				(width 0)
				(type default)
			)
			(fill no)
			(layer "F.CrtYd")
		)
		(fp_line
			(start 0.2794 -0.1016)
			(end -0.2794 -0.1016)
			(stroke
				(width 0.1)
				(type default)
			)
			(layer "F.Fab")
		)
		(fp_line
			(start -0.2794 -0.1016)
			(end -0.2794 0.9906)
			(stroke
				(width 0.1)
				(type default)
			)
			(layer "F.Fab")
		)
		(fp_line
			(start 0.2794 0.9906)
			(end 0.2794 -0.1016)
			(stroke
				(width 0.1)
				(type default)
			)
			(layer "F.Fab")
		)
		(fp_line
			(start -0.2794 0.9906)
			(end 0.2794 0.9906)
			(stroke
				(width 0.1)
				(type default)
			)
			(layer "F.Fab")
		)
		(pad "1" smd rect
			(at 0 0 90)
			(size 0.508 0.508)
			(layers "F.Cu" "F.Mask" "F.Paste")
			(net "PVCCIO_CPU0")
		)
		(pad "2" smd rect
			(at 0 0.889 90)
			(size 0.508 0.508)
			(layers "F.Cu" "F.Mask" "F.Paste")
			(net "GND")
		)
		(zone
			(layer "F.Cu")
			(hatch none 0.5)
			(connect_pads
				(clearance 0)
			)
			(min_thickness 0.25)
			(keepout
				(tracks allowed)
				(vias not_allowed)
				(pads allowed)
				(copperpour not_allowed)
				(footprints allowed)
			)
			(placement
				(enabled no)
				(sheetname "")
			)
			(fill
				(thermal_gap 0.5)
				(thermal_bridge_width 0.5)
				(island_removal_mode 0)
			)
			(polygon
				(pts
					(xy 339.9282 -104.775) (xy 339.9282 -105.283) (xy 340.3092 -105.283) (xy 340.3092 -104.775)
				)
			)
		)
		(zone
			(layer "F.Cu")
			(hatch none 0.5)
			(connect_pads
				(clearance 0)
			)
			(min_thickness 0.25)
			(keepout
				(tracks not_allowed)
				(vias allowed)
				(pads allowed)
				(copperpour not_allowed)
				(footprints allowed)
			)
			(placement
				(enabled no)
				(sheetname "")
			)
			(fill
				(thermal_gap 0.5)
				(thermal_bridge_width 0.5)
				(island_removal_mode 0)
			)
			(polygon
				(pts
					(xy 340.3092 -104.775) (xy 340.3092 -105.283) (xy 339.9282 -105.283) (xy 339.9282 -104.775)
				)
			)
		)
	)
	(footprint ""
		(layer "F.Cu")
		(at 181.991 -32.893 90)
		(property "Reference" "C4F4"
			(at -3.20167 3.429 0)
			(unlocked yes)
			(layer "F.SilkS")
			(effects
				(font
					(size 0.7874 0.5842)
					(thickness 0.1524)
				)
			)
		)
		(property "Value" ""
			(at 0 0 90)
			(layer "F.Fab")
			(effects
				(font
					(size 1.27 1.27)
				)
			)
		)
		(duplicate_pad_numbers_are_jumpers no)
		(fp_line
			(start 2.504948 -1.616456)
			(end 2.504948 1.633728)
			(stroke
				(width 0.1524)
				(type default)
			)
			(layer "F.SilkS")
		)
		(fp_line
			(start 1.6002 -1.616456)
			(end 2.504948 -1.616456)
			(stroke
				(width 0.1524)
				(type default)
			)
			(layer "F.SilkS")
		)
		(fp_line
			(start -1.6002 -1.616456)
			(end -2.563114 -1.616456)
			(stroke
				(width 0.1524)
				(type default)
			)
			(layer "F.SilkS")
		)
		(fp_line
			(start -2.563114 -1.616456)
			(end -2.563114 1.633728)
			(stroke
				(width 0.1524)
				(type default)
			)
			(layer "F.SilkS")
		)
		(fp_line
			(start 2.504948 1.633728)
			(end 1.6002 1.633728)
			(stroke
				(width 0.1524)
				(type default)
			)
			(layer "F.SilkS")
		)
		(fp_line
			(start -2.563114 1.633728)
			(end -1.6002 1.633728)
			(stroke
				(width 0.1524)
				(type default)
			)
			(layer "F.SilkS")
		)
		(fp_line
			(start 2.286 7.366)
			(end 2.286 1.63195)
			(stroke
				(width 0.1524)
				(type default)
			)
			(layer "F.SilkS")
		)
		(fp_line
			(start 2.286 7.366)
			(end 1.600708 7.366)
			(stroke
				(width 0.1524)
				(type default)
			)
			(layer "F.SilkS")
		)
		(fp_line
			(start -2.286 7.366)
			(end -2.286 1.632712)
			(stroke
				(width 0.1524)
				(type default)
			)
			(layer "F.SilkS")
		)
		(fp_line
			(start -2.286 7.366)
			(end -1.60147 7.366)
			(stroke
				(width 0.1524)
				(type default)
			)
			(layer "F.SilkS")
		)
		(fp_rect
			(start -2.286 7.366)
			(end 2.286 -0.254)
			(stroke
				(width 0)
				(type default)
			)
			(fill no)
			(layer "F.CrtYd")
		)
		(fp_line
			(start 2.286 -0.254)
			(end 2.286 7.366)
			(stroke
				(width 0.1)
				(type default)
			)
			(layer "F.Fab")
		)
		(fp_line
			(start -2.286 -0.254)
			(end 2.286 -0.254)
			(stroke
				(width 0.1)
				(type default)
			)
			(layer "F.Fab")
		)
		(fp_line
			(start 2.286 7.366)
			(end -2.286 7.366)
			(stroke
				(width 0.1)
				(type default)
			)
			(layer "F.Fab")
		)
		(fp_line
			(start -2.286 7.366)
			(end -2.286 -0.254)
			(stroke
				(width 0.1)
				(type default)
			)
			(layer "F.Fab")
		)
		(pad "1" smd rect
			(at 0 0 90)
			(size 2.54 3.048)
			(layers "F.Cu" "F.Mask" "F.Paste")
			(net "P12V_STBY")
		)
		(pad "2" smd rect
			(at 0 7.112 90)
			(size 2.54 3.048)
			(layers "F.Cu" "F.Mask" "F.Paste")
			(net "GND")
		)
	)
	(footprint ""
		(layer "F.Cu")
		(at 184.531 -146.685)
		(property "Reference" "C4A12"
			(at 0 0 0)
			(layer "F.SilkS")
			(hide yes)
			(effects
				(font
					(size 1.27 1.27)
				)
			)
		)
		(property "Value" ""
			(at 0 0 0)
			(layer "F.Fab")
			(effects
				(font
					(size 1.27 1.27)
				)
			)
		)
		(duplicate_pad_numbers_are_jumpers no)
		(fp_rect
			(start 0.3048 0.9906)
			(end -0.3048 -0.1016)
			(stroke
				(width 0)
				(type default)
			)
			(fill no)
			(layer "F.CrtYd")
		)
		(fp_line
			(start -0.3048 -0.1016)
			(end -0.3048 0.9906)
			(stroke
				(width 0.1)
				(type default)
			)
			(layer "F.Fab")
		)
		(fp_line
			(start -0.3048 0.9906)
			(end 0.3048 0.9906)
			(stroke
				(width 0.1)
				(type default)
			)
			(layer "F.Fab")
		)
		(fp_line
			(start 0.3048 -0.1016)
			(end -0.3048 -0.1016)
			(stroke
				(width 0.1)
				(type default)
			)
			(layer "F.Fab")
		)
		(fp_line
			(start 0.3048 0.9906)
			(end 0.3048 -0.1016)
			(stroke
				(width 0.1)
				(type default)
			)
			(layer "F.Fab")
		)
		(pad "1" smd rect
			(at 0 0)
			(size 0.508 0.508)
			(layers "F.Cu" "F.Mask" "F.Paste")
			(net "PWRGD_PVTT_DEF_CPU0_R")
		)
		(pad "2" smd rect
			(at 0 0.889)
			(size 0.508 0.508)
			(layers "F.Cu" "F.Mask" "F.Paste")
			(net "GND")
		)
		(zone
			(layer "F.Cu")
			(hatch none 0.5)
			(connect_pads
				(clearance 0)
			)
			(min_thickness 0.25)
			(keepout
				(tracks not_allowed)
				(vias allowed)
				(pads allowed)
				(copperpour not_allowed)
				(footprints allowed)
			)
			(placement
				(enabled no)
				(sheetname "")
			)
			(fill
				(thermal_gap 0.5)
				(thermal_bridge_width 0.5)
				(island_removal_mode 0)
			)
			(polygon
				(pts
					(xy 184.785 -146.05) (xy 184.785 -146.431) (xy 184.277 -146.431) (xy 184.277 -146.05)
				)
			)
		)
		(zone
			(layer "F.Cu")
			(hatch none 0.5)
			(connect_pads
				(clearance 0)
			)
			(min_thickness 0.25)
			(keepout
				(tracks allowed)
				(vias not_allowed)
				(pads allowed)
				(copperpour not_allowed)
				(footprints allowed)
			)
			(placement
				(enabled no)
				(sheetname "")
			)
			(fill
				(thermal_gap 0.5)
				(thermal_bridge_width 0.5)
				(island_removal_mode 0)
			)
			(polygon
				(pts
					(xy 184.785 -146.05) (xy 184.785 -146.431) (xy 184.277 -146.431) (xy 184.277 -146.05)
				)
			)
		)
	)
)
